(kicad_pcb
	(version 20260206)
	(generator "pcbnew")
	(generator_version "10.0")
	(general
		(thickness 1.6)
		(legacy_teardrops no)
	)
	(paper "A4")
	(title_block
		(title "v1-chassis-manager — T6M_CM_d_v01_1031_1645.brd")
		(comment 1 "Open CloudServer (Microsoft) / footprints 1935-1942 of 2512")
	)
	(layers
		(0 "F.Cu" signal "TOP")
		(4 "In1.Cu" signal "GND1")
		(6 "In2.Cu" signal "IN1")
		(8 "In3.Cu" signal "VCC1")
		(10 "In4.Cu" signal "VCC2")
		(12 "In5.Cu" signal "GND2")
		(14 "In6.Cu" signal "IN2")
		(16 "In7.Cu" signal "IN3")
		(18 "In8.Cu" signal "GND3")
		(2 "B.Cu" signal "BOTTOM")
		(9 "F.Adhes" user "F.Adhesive")
		(11 "B.Adhes" user "B.Adhesive")
		(13 "F.Paste" user "Package Geometry/Pastemask Top")
		(15 "B.Paste" user "Package Geometry/Pastemask Bottom")
		(5 "F.SilkS" user "Ref Des/Silkscreen Top")
		(7 "B.SilkS" user "Ref Des/Silkscreen Bottom")
		(1 "F.Mask" user "Board Geometry/Soldermask Top")
		(3 "B.Mask" user "Board Geometry/Soldermask Bottom")
		(17 "Dwgs.User" user "User.Drawings")
		(19 "Cmts.User" user "User.Comments")
		(21 "Eco1.User" user "User.Eco1")
		(23 "Eco2.User" user "User.Eco2")
		(25 "Edge.Cuts" user "Board Geometry/Outline")
		(27 "Margin" user)
		(31 "F.CrtYd" user "Package Geometry/Place Bound Top")
		(29 "B.CrtYd" user "Package Geometry/Place Bound Bottom")
		(35 "F.Fab" user "Ref Des/Assembly Top")
		(33 "B.Fab" user "Ref Des/Assembly Bottom")
	)
	(footprint ""
		(layer "B.Cu")
		(at 105.191814 -112.98682)
		(property "Reference" "PC112"
			(at -3.119374 0.182118 0)
			(unlocked yes)
			(layer "B.SilkS")
			(effects
				(font
					(size 0.7874 0.5842)
					(thickness 0.1524)
				)
				(justify left mirror)
			)
		)
		(property "Value" ""
			(at 0 0 0)
			(layer "B.Fab")
			(effects
				(font
					(size 1.27 1.27)
				)
				(justify mirror)
			)
		)
		(duplicate_pad_numbers_are_jumpers no)
		(fp_line
			(start -1.905 -0.8636)
			(end -1.905 0.8636)
			(stroke
				(width 0.1524)
				(type default)
			)
			(layer "B.SilkS")
		)
		(fp_line
			(start -1.905 0.8636)
			(end 1.905 0.8636)
			(stroke
				(width 0.1524)
				(type default)
			)
			(layer "B.SilkS")
		)
		(fp_line
			(start 0 0.8382)
			(end 0 -0.8382)
			(stroke
				(width 0.1524)
				(type default)
			)
			(layer "B.SilkS")
		)
		(fp_line
			(start 1.905 -0.8636)
			(end -1.905 -0.8636)
			(stroke
				(width 0.1524)
				(type default)
			)
			(layer "B.SilkS")
		)
		(fp_line
			(start 1.905 0.8636)
			(end 1.905 -0.8636)
			(stroke
				(width 0.1524)
				(type default)
			)
			(layer "B.SilkS")
		)
		(fp_rect
			(start 1.524 0.7366)
			(end -1.524 -0.7366)
			(stroke
				(width 0)
				(type default)
			)
			(fill no)
			(layer "B.CrtYd")
		)
		(pad "1" smd rect
			(at -0.94996 0 180)
			(size 1.1176 1.3716)
			(layers "B.Cu" "B.Mask" "B.Paste")
			(net "GND")
		)
		(pad "2" smd rect
			(at 0.94996 0 180)
			(size 1.1176 1.3716)
			(layers "B.Cu" "B.Mask" "B.Paste")
			(net "PV_VCCP_NODE1")
		)
	)
	(footprint ""
		(layer "B.Cu")
		(at 110.686342 -67.025012 90)
		(property "Reference" "R224"
			(at 1.025652 -0.039116 270)
			(unlocked yes)
			(layer "B.SilkS")
			(effects
				(font
					(size 0.7874 0.5842)
					(thickness 0.1524)
				)
				(justify left mirror)
			)
		)
		(property "Value" ""
			(at 0 0 90)
			(layer "B.Fab")
			(effects
				(font
					(size 1.27 1.27)
				)
				(justify mirror)
			)
		)
		(duplicate_pad_numbers_are_jumpers no)
		(fp_line
			(start 0.7874 -0.4064)
			(end -0.7874 -0.4064)
			(stroke
				(width 0.1524)
				(type default)
			)
			(layer "B.SilkS")
		)
		(fp_line
			(start -0.7874 -0.4064)
			(end -0.7874 0.4064)
			(stroke
				(width 0.1524)
				(type default)
			)
			(layer "B.SilkS")
		)
		(fp_line
			(start 0.7874 0.4064)
			(end 0.7874 -0.4064)
			(stroke
				(width 0.1524)
				(type default)
			)
			(layer "B.SilkS")
		)
		(fp_line
			(start -0.7874 0.4064)
			(end 0.7874 0.4064)
			(stroke
				(width 0.1524)
				(type default)
			)
			(layer "B.SilkS")
		)
		(fp_poly
			(pts
				(xy 0.508 0.2794) (xy 0.508 0.2286) (xy 0.635 0.2286) (xy 0.635 -0.254) (xy 0.5334 -0.254) (xy 0.5334 -0.2794)
				(xy -0.5334 -0.2794) (xy -0.5334 -0.254) (xy -0.635 -0.254) (xy -0.635 0.254) (xy -0.5334 0.254)
				(xy -0.5334 0.2794)
			)
			(stroke
				(width 0)
				(type default)
			)
			(fill no)
			(layer "B.CrtYd")
		)
		(pad "1" smd rect
			(at -0.40005 0 270)
			(size 0.4572 0.508)
			(layers "B.Cu" "B.Mask" "B.Paste")
			(net "P1V05_STB_NODE1_XDP_A")
		)
		(pad "2" smd rect
			(at 0.40005 0 270)
			(size 0.4572 0.508)
			(layers "B.Cu" "B.Mask" "B.Paste")
			(net "P1V05_NODE1")
		)
	)
	(footprint ""
		(layer "B.Cu")
		(at 144.747996 -59.96813 90)
		(property "Reference" "C354"
			(at 1.168908 -0.368046 270)
			(unlocked yes)
			(layer "B.SilkS")
			(effects
				(font
					(size 0.7874 0.5842)
					(thickness 0.1524)
				)
				(justify left mirror)
			)
		)
		(property "Value" ""
			(at 0 0 90)
			(layer "B.Fab")
			(effects
				(font
					(size 1.27 1.27)
				)
				(justify mirror)
			)
		)
		(duplicate_pad_numbers_are_jumpers no)
		(fp_line
			(start 0.7874 -0.4064)
			(end -0.7874 -0.4064)
			(stroke
				(width 0.1524)
				(type default)
			)
			(layer "B.SilkS")
		)
		(fp_line
			(start -0.7874 -0.4064)
			(end -0.7874 0.4064)
			(stroke
				(width 0.1524)
				(type default)
			)
			(layer "B.SilkS")
		)
		(fp_line
			(start 0 0.381)
			(end 0 -0.381)
			(stroke
				(width 0.1524)
				(type default)
			)
			(layer "B.SilkS")
		)
		(fp_line
			(start 0.7874 0.4064)
			(end 0.7874 -0.4064)
			(stroke
				(width 0.1524)
				(type default)
			)
			(layer "B.SilkS")
		)
		(fp_line
			(start -0.7874 0.4064)
			(end 0.7874 0.4064)
			(stroke
				(width 0.1524)
				(type default)
			)
			(layer "B.SilkS")
		)
		(fp_poly
			(pts
				(xy 0.5334 0.254) (xy 0.635 0.254) (xy 0.635 0.2286) (xy 0.635 -0.254) (xy 0.5334 -0.254) (xy 0.5334 -0.2794)
				(xy -0.5334 -0.2794) (xy -0.5334 -0.254) (xy -0.635 -0.254) (xy -0.635 0.254) (xy -0.5334 0.254)
				(xy -0.5334 0.2794) (xy 0.508 0.2794) (xy 0.5334 0.2794)
			)
			(stroke
				(width 0)
				(type default)
			)
			(fill no)
			(layer "B.CrtYd")
		)
		(pad "1" smd rect
			(at -0.40005 0 270)
			(size 0.4572 0.508)
			(layers "B.Cu" "B.Mask" "B.Paste")
			(net "P3V3_NODE1")
		)
		(pad "2" smd rect
			(at 0.40005 0 270)
			(size 0.4572 0.508)
			(layers "B.Cu" "B.Mask" "B.Paste")
			(net "GND")
		)
	)
	(footprint ""
		(layer "B.Cu")
		(at 84.82076 -173.394624 -90)
		(property "Reference" "U62"
			(at 22.479254 -27.045412 0)
			(unlocked yes)
			(layer "B.SilkS")
			(effects
				(font
					(size 0.7874 0.5842)
					(thickness 0.1524)
				)
				(justify left mirror)
			)
		)
		(property "Value" ""
			(at 0 0 90)
			(layer "B.Fab")
			(effects
				(font
					(size 1.27 1.27)
				)
				(justify mirror)
			)
		)
		(duplicate_pad_numbers_are_jumpers no)
		(fp_line
			(start -3.9624 2.0066)
			(end 3.9624 2.0066)
			(stroke
				(width 0.1524)
				(type default)
			)
			(layer "B.SilkS")
		)
		(fp_line
			(start 3.9624 2.0066)
			(end 3.9624 0.5842)
			(stroke
				(width 0.1524)
				(type default)
			)
			(layer "B.SilkS")
		)
		(fp_line
			(start 3.9624 0.5842)
			(end 3.3782 0)
			(stroke
				(width 0.1524)
				(type default)
			)
			(layer "B.SilkS")
		)
		(fp_line
			(start 3.3782 0)
			(end 3.9624 -0.5842)
			(stroke
				(width 0.1524)
				(type default)
			)
			(layer "B.SilkS")
		)
		(fp_line
			(start 3.9624 -0.5842)
			(end 3.9624 -2.0066)
			(stroke
				(width 0.1524)
				(type default)
			)
			(layer "B.SilkS")
		)
		(fp_line
			(start -3.9624 -2.0066)
			(end -3.9624 2.0066)
			(stroke
				(width 0.1524)
				(type default)
			)
			(layer "B.SilkS")
		)
		(fp_line
			(start 3.9624 -2.0066)
			(end -3.9624 -2.0066)
			(stroke
				(width 0.1524)
				(type default)
			)
			(layer "B.SilkS")
		)
		(fp_circle
			(center 3.429 1.524)
			(end 3.429 1.27)
			(stroke
				(width 0.1524)
				(type default)
			)
			(fill no)
			(layer "B.SilkS")
		)
		(fp_poly
			(pts
				(xy 3.962654 3.6703) (xy 3.974846 -3.6703) (xy -3.9624 -3.6703) (xy -3.9624 3.6703)
			)
			(stroke
				(width 0)
				(type default)
			)
			(fill no)
			(layer "B.CrtYd")
		)
		(pad "1" smd rect
			(at 3.57505 2.921 90)
			(size 0.3556 1.4986)
			(layers "B.Cu" "B.Mask" "B.Paste")
			(net "N21699285")
		)
		(pad "2" smd rect
			(at 2.925064 2.921 90)
			(size 0.3556 1.4986)
			(layers "B.Cu" "B.Mask" "B.Paste")
			(net "N21700927")
		)
		(pad "3" smd rect
			(at 2.275078 2.921 90)
			(size 0.3556 1.4986)
			(layers "B.Cu" "B.Mask" "B.Paste")
			(net "N21700927")
		)
		(pad "4" smd rect
			(at 1.625092 2.921 90)
			(size 0.3556 1.4986)
			(layers "B.Cu" "B.Mask" "B.Paste")
			(net "T1_NODE1_EN")
		)
		(pad "5" smd rect
			(at 0.975106 2.921 90)
			(size 0.3556 1.4986)
			(layers "B.Cu" "B.Mask" "B.Paste")
			(net "T1_NODE2_EN")
		)
		(pad "6" smd rect
			(at 0.32512 2.921 90)
			(size 0.3556 1.4986)
			(layers "B.Cu" "B.Mask" "B.Paste")
			(net "T1_NODE3_EN")
		)
		(pad "7" smd rect
			(at -0.32512 2.921 90)
			(size 0.3556 1.4986)
			(layers "B.Cu" "B.Mask" "B.Paste")
			(net "T1_NODE4_EN")
		)
		(pad "8" smd rect
			(at -0.975106 2.921 90)
			(size 0.3556 1.4986)
			(layers "B.Cu" "B.Mask" "B.Paste")
			(net "T2_NODE1_EN")
		)
		(pad "9" smd rect
			(at -1.625092 2.921 90)
			(size 0.3556 1.4986)
			(layers "B.Cu" "B.Mask" "B.Paste")
			(net "T2_NODE2_EN")
		)
		(pad "10" smd rect
			(at -2.275078 2.921 90)
			(size 0.3556 1.4986)
			(layers "B.Cu" "B.Mask" "B.Paste")
			(net "T2_NODE3_EN")
		)
		(pad "11" smd rect
			(at -2.925064 2.921 90)
			(size 0.3556 1.4986)
			(layers "B.Cu" "B.Mask" "B.Paste")
			(net "T2_NODE4_EN")
		)
		(pad "12" smd rect
			(at -3.57505 2.921 90)
			(size 0.3556 1.4986)
			(layers "B.Cu" "B.Mask" "B.Paste")
			(net "GND")
		)
		(pad "13" smd rect
			(at -3.57505 -2.921 90)
			(size 0.3556 1.4986)
			(layers "B.Cu" "B.Mask" "B.Paste")
			(net "T3_NODE1_EN")
		)
		(pad "14" smd rect
			(at -2.925064 -2.921 90)
			(size 0.3556 1.4986)
			(layers "B.Cu" "B.Mask" "B.Paste")
			(net "T3_NODE2_EN")
		)
		(pad "15" smd rect
			(at -2.275078 -2.921 90)
			(size 0.3556 1.4986)
			(layers "B.Cu" "B.Mask" "B.Paste")
			(net "T3_NODE3_EN")
		)
		(pad "16" smd rect
			(at -1.625092 -2.921 90)
			(size 0.3556 1.4986)
			(layers "B.Cu" "B.Mask" "B.Paste")
			(net "T3_NODE4_EN")
		)
		(pad "17" smd rect
			(at -0.975106 -2.921 90)
			(size 0.3556 1.4986)
			(layers "B.Cu" "B.Mask" "B.Paste")
			(net "T4_NODE1_EN")
		)
		(pad "18" smd rect
			(at -0.32512 -2.921 90)
			(size 0.3556 1.4986)
			(layers "B.Cu" "B.Mask" "B.Paste")
			(net "T4_NODE2_EN")
		)
		(pad "19" smd rect
			(at 0.32512 -2.921 90)
			(size 0.3556 1.4986)
			(layers "B.Cu" "B.Mask" "B.Paste")
			(net "T4_NODE3_EN")
		)
		(pad "20" smd rect
			(at 0.975106 -2.921 90)
			(size 0.3556 1.4986)
			(layers "B.Cu" "B.Mask" "B.Paste")
			(net "T4_NODE4_EN")
		)
		(pad "21" smd rect
			(at 1.625092 -2.921 90)
			(size 0.3556 1.4986)
			(layers "B.Cu" "B.Mask" "B.Paste")
			(net "N21700927")
		)
		(pad "22" smd rect
			(at 2.275078 -2.921 90)
			(size 0.3556 1.4986)
			(layers "B.Cu" "B.Mask" "B.Paste")
			(net "I2C_COM3_SCL")
		)
		(pad "23" smd rect
			(at 2.925064 -2.921 90)
			(size 0.3556 1.4986)
			(layers "B.Cu" "B.Mask" "B.Paste")
			(net "I2C_COM3_SDA")
		)
		(pad "24" smd rect
			(at 3.57505 -2.921 90)
			(size 0.3556 1.4986)
			(layers "B.Cu" "B.Mask" "B.Paste")
			(net "P3V3_NODE1")
		)
	)
	(footprint ""
		(layer "B.Cu")
		(at 49.64176 -179.871624)
		(property "Reference" "C569"
			(at -1.279652 -0.008128 0)
			(unlocked yes)
			(layer "B.SilkS")
			(effects
				(font
					(size 0.7874 0.5842)
					(thickness 0.1524)
				)
				(justify left mirror)
			)
		)
		(property "Value" ""
			(at 0 0 0)
			(layer "B.Fab")
			(effects
				(font
					(size 1.27 1.27)
				)
				(justify mirror)
			)
		)
		(duplicate_pad_numbers_are_jumpers no)
		(fp_line
			(start -0.7874 -0.4064)
			(end -0.7874 0.4064)
			(stroke
				(width 0.1524)
				(type default)
			)
			(layer "B.SilkS")
		)
		(fp_line
			(start -0.7874 0.4064)
			(end 0.7874 0.4064)
			(stroke
				(width 0.1524)
				(type default)
			)
			(layer "B.SilkS")
		)
		(fp_line
			(start 0 0.381)
			(end 0 -0.381)
			(stroke
				(width 0.1524)
				(type default)
			)
			(layer "B.SilkS")
		)
		(fp_line
			(start 0.7874 -0.4064)
			(end -0.7874 -0.4064)
			(stroke
				(width 0.1524)
				(type default)
			)
			(layer "B.SilkS")
		)
		(fp_line
			(start 0.7874 0.4064)
			(end 0.7874 -0.4064)
			(stroke
				(width 0.1524)
				(type default)
			)
			(layer "B.SilkS")
		)
		(fp_poly
			(pts
				(xy 0.5334 0.254) (xy 0.635 0.254) (xy 0.635 0.2286) (xy 0.635 -0.254) (xy 0.5334 -0.254) (xy 0.5334 -0.2794)
				(xy -0.5334 -0.2794) (xy -0.5334 -0.254) (xy -0.635 -0.254) (xy -0.635 0.254) (xy -0.5334 0.254)
				(xy -0.5334 0.2794) (xy 0.508 0.2794) (xy 0.5334 0.2794)
			)
			(stroke
				(width 0)
				(type default)
			)
			(fill no)
			(layer "B.CrtYd")
		)
		(pad "1" smd rect
			(at -0.40005 0 180)
			(size 0.4572 0.508)
			(layers "B.Cu" "B.Mask" "B.Paste")
			(net "GND")
		)
		(pad "2" smd rect
			(at 0.40005 0 180)
			(size 0.4572 0.508)
			(layers "B.Cu" "B.Mask" "B.Paste")
			(net "P3V3_NODE1")
		)
	)
	(footprint ""
		(layer "B.Cu")
		(at 83.58886 -79.213456)
		(property "Reference" "R127"
			(at 0.816864 -1.071626 0)
			(unlocked yes)
			(layer "B.SilkS")
			(effects
				(font
					(size 0.7874 0.5842)
					(thickness 0.1524)
				)
				(justify left mirror)
			)
		)
		(property "Value" ""
			(at 0 0 0)
			(layer "B.Fab")
			(effects
				(font
					(size 1.27 1.27)
				)
				(justify mirror)
			)
		)
		(duplicate_pad_numbers_are_jumpers no)
		(fp_line
			(start -0.7874 -0.4064)
			(end -0.7874 0.4064)
			(stroke
				(width 0.1524)
				(type default)
			)
			(layer "B.SilkS")
		)
		(fp_line
			(start -0.7874 0.4064)
			(end 0.7874 0.4064)
			(stroke
				(width 0.1524)
				(type default)
			)
			(layer "B.SilkS")
		)
		(fp_line
			(start 0.7874 -0.4064)
			(end -0.7874 -0.4064)
			(stroke
				(width 0.1524)
				(type default)
			)
			(layer "B.SilkS")
		)
		(fp_line
			(start 0.7874 0.4064)
			(end 0.7874 -0.4064)
			(stroke
				(width 0.1524)
				(type default)
			)
			(layer "B.SilkS")
		)
		(fp_poly
			(pts
				(xy 0.508 0.2794) (xy 0.508 0.2286) (xy 0.635 0.2286) (xy 0.635 -0.254) (xy 0.5334 -0.254) (xy 0.5334 -0.2794)
				(xy -0.5334 -0.2794) (xy -0.5334 -0.254) (xy -0.635 -0.254) (xy -0.635 0.254) (xy -0.5334 0.254)
				(xy -0.5334 0.2794)
			)
			(stroke
				(width 0)
				(type default)
			)
			(fill no)
			(layer "B.CrtYd")
		)
		(pad "1" smd rect
			(at -0.40005 0 180)
			(size 0.4572 0.508)
			(layers "B.Cu" "B.Mask" "B.Paste")
			(net "SVID_CPU_NODE1_PVCCP_DAT")
		)
		(pad "2" smd rect
			(at 0.40005 0 180)
			(size 0.4572 0.508)
			(layers "B.Cu" "B.Mask" "B.Paste")
			(net "P1V05_NODE1")
		)
	)
	(footprint ""
		(layer "B.Cu")
		(at 67.67576 -188.126624 -90)
		(property "Reference" "C692"
			(at -4.308602 0.378206 270)
			(unlocked yes)
			(layer "B.SilkS")
			(effects
				(font
					(size 0.7874 0.5842)
					(thickness 0.1524)
				)
				(justify left mirror)
			)
		)
		(property "Value" ""
			(at 0 0 90)
			(layer "B.Fab")
			(effects
				(font
					(size 1.27 1.27)
				)
				(justify mirror)
			)
		)
		(duplicate_pad_numbers_are_jumpers no)
		(fp_line
			(start -0.7874 0.4064)
			(end 0.7874 0.4064)
			(stroke
				(width 0.1524)
				(type default)
			)
			(layer "B.SilkS")
		)
		(fp_line
			(start 0.7874 0.4064)
			(end 0.7874 -0.4064)
			(stroke
				(width 0.1524)
				(type default)
			)
			(layer "B.SilkS")
		)
		(fp_line
			(start 0 0.381)
			(end 0 -0.381)
			(stroke
				(width 0.1524)
				(type default)
			)
			(layer "B.SilkS")
		)
		(fp_line
			(start -0.7874 -0.4064)
			(end -0.7874 0.4064)
			(stroke
				(width 0.1524)
				(type default)
			)
			(layer "B.SilkS")
		)
		(fp_line
			(start 0.7874 -0.4064)
			(end -0.7874 -0.4064)
			(stroke
				(width 0.1524)
				(type default)
			)
			(layer "B.SilkS")
		)
		(fp_poly
			(pts
				(xy 0.5334 0.254) (xy 0.635 0.254) (xy 0.635 0.2286) (xy 0.635 -0.254) (xy 0.5334 -0.254) (xy 0.5334 -0.2794)
				(xy -0.5334 -0.2794) (xy -0.5334 -0.254) (xy -0.635 -0.254) (xy -0.635 0.254) (xy -0.5334 0.254)
				(xy -0.5334 0.2794) (xy 0.508 0.2794) (xy 0.5334 0.2794)
			)
			(stroke
				(width 0)
				(type default)
			)
			(fill no)
			(layer "B.CrtYd")
		)
		(pad "1" smd rect
			(at -0.40005 0 90)
			(size 0.4572 0.508)
			(layers "B.Cu" "B.Mask" "B.Paste")
			(net "UART_T3_NODE4_TXD_R")
		)
		(pad "2" smd rect
			(at 0.40005 0 90)
			(size 0.4572 0.508)
			(layers "B.Cu" "B.Mask" "B.Paste")
			(net "GND")
		)
	)
	(footprint ""
		(layer "B.Cu")
		(at 140.760196 -65.55613)
		(property "Reference" "C342"
			(at 1.533652 -1.064006 0)
			(unlocked yes)
			(layer "B.SilkS")
			(effects
				(font
					(size 0.7874 0.5842)
					(thickness 0.1524)
				)
				(justify left mirror)
			)
		)
		(property "Value" ""
			(at 0 0 0)
			(layer "B.Fab")
			(effects
				(font
					(size 1.27 1.27)
				)
				(justify mirror)
			)
		)
		(duplicate_pad_numbers_are_jumpers no)
		(fp_line
			(start -0.7874 -0.4064)
			(end -0.7874 0.4064)
			(stroke
				(width 0.1524)
				(type default)
			)
			(layer "B.SilkS")
		)
		(fp_line
			(start -0.7874 0.4064)
			(end 0.7874 0.4064)
			(stroke
				(width 0.1524)
				(type default)
			)
			(layer "B.SilkS")
		)
		(fp_line
			(start 0 0.381)
			(end 0 -0.381)
			(stroke
				(width 0.1524)
				(type default)
			)
			(layer "B.SilkS")
		)
		(fp_line
			(start 0.7874 -0.4064)
			(end -0.7874 -0.4064)
			(stroke
				(width 0.1524)
				(type default)
			)
			(layer "B.SilkS")
		)
		(fp_line
			(start 0.7874 0.4064)
			(end 0.7874 -0.4064)
			(stroke
				(width 0.1524)
				(type default)
			)
			(layer "B.SilkS")
		)
		(fp_poly
			(pts
				(xy 0.5334 0.254) (xy 0.635 0.254) (xy 0.635 0.2286) (xy 0.635 -0.254) (xy 0.5334 -0.254) (xy 0.5334 -0.2794)
				(xy -0.5334 -0.2794) (xy -0.5334 -0.254) (xy -0.635 -0.254) (xy -0.635 0.254) (xy -0.5334 0.254)
				(xy -0.5334 0.2794) (xy 0.508 0.2794) (xy 0.5334 0.2794)
			)
			(stroke
				(width 0)
				(type default)
			)
			(fill no)
			(layer "B.CrtYd")
		)
		(pad "1" smd rect
			(at -0.40005 0 180)
			(size 0.4572 0.508)
			(layers "B.Cu" "B.Mask" "B.Paste")
			(net "P1V0_SATA")
		)
		(pad "2" smd rect
			(at 0.40005 0 180)
			(size 0.4572 0.508)
			(layers "B.Cu" "B.Mask" "B.Paste")
			(net "GND")
		)
	)
)
